(kicad_pcb
	(version 20221018)
	(generator pcbnew)
	(general
    (thickness 1.518)
  )
	(paper "A4")
	(title_block
    (title "Kria K26 Devboard")
    (date "2024-03-26")
    (rev "1.2.5")
    (comment 1 "www.antmicro.com")
    (comment 2 "Antmicro Ltd.")
		(comment 9 "footprint 78 of 660 (J_SOM240_2), pads 1-100 of 242")
	)
	(layers
    (0 "F.Cu" mixed)
    (1 "In1.Cu" power)
    (2 "In2.Cu" mixed)
    (3 "In3.Cu" power)
    (4 "In4.Cu" mixed)
    (5 "In5.Cu" power)
    (6 "In6.Cu" mixed)
    (31 "B.Cu" power)
    (32 "B.Adhes" user "B.Adhesive")
    (33 "F.Adhes" user "F.Adhesive")
    (34 "B.Paste" user)
    (35 "F.Paste" user)
    (36 "B.SilkS" user "B.Silkscreen")
    (37 "F.SilkS" user "F.Silkscreen")
    (38 "B.Mask" user)
    (39 "F.Mask" user)
    (40 "Dwgs.User" user "User.Drawings")
    (41 "Cmts.User" user "User.Comments")
    (42 "Eco1.User" user "User.Eco1")
    (43 "Eco2.User" user "User.Eco2")
    (44 "Edge.Cuts" user)
    (45 "Margin" user)
    (46 "B.CrtYd" user "B.Courtyard")
    (47 "F.CrtYd" user "F.Courtyard")
    (48 "B.Fab" user)
    (49 "F.Fab" user)
  )
	(footprint "kria-k26-devboard-footprints:Conn_Plug_Samtec_ADM6_4x60_ADM6-60-01.5-L-4-2-A-TR"
    (layer "F.Cu")
    (at 158.177 117.6205 -90)
    (property "Author" "Antmicro")
    (property "DNP" "DNP")
    (property "License" "Apache-2.0")
    (property "MPN" "ADM6-60-01.5-L-4-2-A-TR")
    (property "Manufacturer" "Samtec")
    (property "Sheetfile" "k26_som.kicad_sch")
    (property "Sheetname" "Xilinx K26 SOM")
    (property "dnp" "")
    (property "exclude_from_bom" "")
    (property "ki_description" "Board to Board & Mezzanine Connectors 0.635 mm AcceleRate HD High-Density 4-Row Header 60P")
    (attr exclude_from_pos_files exclude_from_bom)
    (fp_text reference "J_SOM240_2" (at -14.0505 -3.623 90) (layer "F.SilkS")
        (effects (font (size 0.7 0.7) (thickness 0.15)) (justify right bottom))
    )
    (fp_text value "ADM6-60-01.5-L-4-2-A-TR" (at 0 3.7 90) (layer "F.Fab") hide
        (effects (font (size 0.7 0.7) (thickness 0.15)) (justify right bottom))
    )
    (pad "" np_thru_hole circle (at -20.136 -1.27 270) (size 0.95 0.95) (drill 0.95) (layers "*.Cu" "*.Mask"))
    (pad "" np_thru_hole circle (at 20.135 0 270) (size 0.95 0.95) (drill 0.95) (layers "*.Cu" "*.Mask"))
    (pad "A01" smd circle (at 18.732 -1.75 270) (size 0.356 0.356) (layers "F.Cu" "F.Paste" "F.Mask")
      (net 1 "GND") (pinfunction "A01") (pintype "passive"))
    (pad "A02" smd circle (at 18.097 -1.75 270) (size 0.356 0.356) (layers "F.Cu" "F.Paste" "F.Mask")
      (net 1 "GND") (pinfunction "A02") (pintype "passive"))
    (pad "A03" smd circle (at 17.462 -1.75 270) (size 0.356 0.356) (layers "F.Cu" "F.Paste" "F.Mask")
      (net 478 "/Xilinx K26 SOM/GTH_DP3_M2C_P") (pinfunction "A03") (pintype "passive"))
    (pad "A04" smd circle (at 16.827 -1.75 270) (size 0.356 0.356) (layers "F.Cu" "F.Paste" "F.Mask")
      (net 479 "/Xilinx K26 SOM/GTH_DP3_M2C_N") (pinfunction "A04") (pintype "passive"))
    (pad "A05" smd circle (at 16.192 -1.75 270) (size 0.356 0.356) (layers "F.Cu" "F.Paste" "F.Mask")
      (net 1 "GND") (pinfunction "A05") (pintype "passive"))
    (pad "A06" smd circle (at 15.557 -1.75 270) (size 0.356 0.356) (layers "F.Cu" "F.Paste" "F.Mask")
      (net 1 "GND") (pinfunction "A06") (pintype "passive"))
    (pad "A07" smd circle (at 14.922 -1.75 270) (size 0.356 0.356) (layers "F.Cu" "F.Paste" "F.Mask")
      (net 480 "/Xilinx K26 SOM/GTH_REFCLK1_C2M_P") (pinfunction "A07") (pintype "passive"))
    (pad "A08" smd circle (at 14.287 -1.75 270) (size 0.356 0.356) (layers "F.Cu" "F.Paste" "F.Mask")
      (net 481 "/Xilinx K26 SOM/GTH_REFCLK1_C2M_N") (pinfunction "A08") (pintype "passive"))
    (pad "A09" smd circle (at 13.652 -1.75 270) (size 0.356 0.356) (layers "F.Cu" "F.Paste" "F.Mask")
      (net 1 "GND") (pinfunction "A09") (pintype "passive"))
    (pad "A10" smd circle (at 13.017 -1.75 270) (size 0.356 0.356) (layers "F.Cu" "F.Paste" "F.Mask")
      (net 1 "GND") (pinfunction "A10") (pintype "passive"))
    (pad "A11" smd circle (at 12.382 -1.75 270) (size 0.356 0.356) (layers "F.Cu" "F.Paste" "F.Mask")
      (net 482 "/Xilinx K26 SOM/HPB15_CC_P") (pinfunction "A11") (pintype "passive"))
    (pad "A12" smd circle (at 11.747 -1.75 270) (size 0.356 0.356) (layers "F.Cu" "F.Paste" "F.Mask")
      (net 483 "/Xilinx K26 SOM/HPB_15_CC_N") (pinfunction "A12") (pintype "passive"))
    (pad "A13" smd circle (at 11.112 -1.75 270) (size 0.356 0.356) (layers "F.Cu" "F.Paste" "F.Mask")
      (net 1 "GND") (pinfunction "A13") (pintype "passive"))
    (pad "A14" smd circle (at 10.477 -1.75 270) (size 0.356 0.356) (layers "F.Cu" "F.Paste" "F.Mask")
      (net 484 "/Xilinx K26 SOM/HPB08_P") (pinfunction "A14") (pintype "passive"))
    (pad "A15" smd circle (at 9.842 -1.75 270) (size 0.356 0.356) (layers "F.Cu" "F.Paste" "F.Mask")
      (net 485 "/Xilinx K26 SOM/HPB08_N") (pinfunction "A15") (pintype "passive"))
    (pad "A16" smd circle (at 9.207 -1.75 270) (size 0.356 0.356) (layers "F.Cu" "F.Paste" "F.Mask")
      (net 1 "GND") (pinfunction "A16") (pintype "passive"))
    (pad "A17" smd circle (at 8.572 -1.75 270) (size 0.356 0.356) (layers "F.Cu" "F.Paste" "F.Mask")
      (net 486 "/Xilinx K26 SOM/HPB12_P") (pinfunction "A17") (pintype "passive"))
    (pad "A18" smd circle (at 7.937 -1.75 270) (size 0.356 0.356) (layers "F.Cu" "F.Paste" "F.Mask")
      (net 487 "/Xilinx K26 SOM/HPB12_N") (pinfunction "A18") (pintype "passive"))
    (pad "A19" smd circle (at 7.302 -1.75 270) (size 0.356 0.356) (layers "F.Cu" "F.Paste" "F.Mask")
      (net 1 "GND") (pinfunction "A19") (pintype "passive"))
    (pad "A20" smd circle (at 6.667 -1.75 270) (size 0.356 0.356) (layers "F.Cu" "F.Paste" "F.Mask")
      (net 488 "/Xilinx K26 SOM/HPB06_P") (pinfunction "A20") (pintype "passive"))
    (pad "A21" smd circle (at 6.032 -1.75 270) (size 0.356 0.356) (layers "F.Cu" "F.Paste" "F.Mask")
      (net 489 "/Xilinx K26 SOM/HPB06_N") (pinfunction "A21") (pintype "passive"))
    (pad "A22" smd circle (at 5.397 -1.75 270) (size 0.356 0.356) (layers "F.Cu" "F.Paste" "F.Mask")
      (net 1 "GND") (pinfunction "A22") (pintype "passive"))
    (pad "A23" smd circle (at 4.762 -1.75 270) (size 0.356 0.356) (layers "F.Cu" "F.Paste" "F.Mask")
      (net 490 "/Xilinx K26 SOM/HPB16_P") (pinfunction "A23") (pintype "passive"))
    (pad "A24" smd circle (at 4.127 -1.75 270) (size 0.356 0.356) (layers "F.Cu" "F.Paste" "F.Mask")
      (net 491 "/Xilinx K26 SOM/HPB16_N") (pinfunction "A24") (pintype "passive"))
    (pad "A25" smd circle (at 3.492 -1.75 270) (size 0.356 0.356) (layers "F.Cu" "F.Paste" "F.Mask")
      (net 1 "GND") (pinfunction "A25") (pintype "passive"))
    (pad "A26" smd circle (at 2.857 -1.75 270) (size 0.356 0.356) (layers "F.Cu" "F.Paste" "F.Mask")
      (net 492 "/Xilinx K26 SOM/HPB19_P") (pinfunction "A26") (pintype "passive"))
    (pad "A27" smd circle (at 2.222 -1.75 270) (size 0.356 0.356) (layers "F.Cu" "F.Paste" "F.Mask")
      (net 493 "/Xilinx K26 SOM/HPB19_N") (pinfunction "A27") (pintype "passive"))
    (pad "A28" smd circle (at 1.587 -1.75 270) (size 0.356 0.356) (layers "F.Cu" "F.Paste" "F.Mask")
      (net 1 "GND") (pinfunction "A28") (pintype "passive"))
    (pad "A29" smd circle (at 0.952 -1.75 270) (size 0.356 0.356) (layers "F.Cu" "F.Paste" "F.Mask")
      (net 494 "/Xilinx K26 SOM/HPC08_P") (pinfunction "A29") (pintype "passive"))
    (pad "A30" smd circle (at 0.317 -1.75 270) (size 0.356 0.356) (layers "F.Cu" "F.Paste" "F.Mask")
      (net 495 "/Xilinx K26 SOM/HPC08_N") (pinfunction "A30") (pintype "passive"))
    (pad "A31" smd circle (at -0.318 -1.75 270) (size 0.356 0.356) (layers "F.Cu" "F.Paste" "F.Mask")
      (net 1 "GND") (pinfunction "A31") (pintype "passive"))
    (pad "A32" smd circle (at -0.953 -1.75 270) (size 0.356 0.356) (layers "F.Cu" "F.Paste" "F.Mask")
      (net 496 "/Xilinx K26 SOM/HPC19_P") (pinfunction "A32") (pintype "passive"))
    (pad "A33" smd circle (at -1.588 -1.75 270) (size 0.356 0.356) (layers "F.Cu" "F.Paste" "F.Mask")
      (net 497 "/Xilinx K26 SOM/HPC19_N") (pinfunction "A33") (pintype "passive"))
    (pad "A34" smd circle (at -2.223 -1.75 270) (size 0.356 0.356) (layers "F.Cu" "F.Paste" "F.Mask")
      (net 1 "GND") (pinfunction "A34") (pintype "passive"))
    (pad "A35" smd circle (at -2.858 -1.75 270) (size 0.356 0.356) (layers "F.Cu" "F.Paste" "F.Mask")
      (net 498 "/Xilinx K26 SOM/HPC14_P") (pinfunction "A35") (pintype "passive"))
    (pad "A36" smd circle (at -3.493 -1.75 270) (size 0.356 0.356) (layers "F.Cu" "F.Paste" "F.Mask")
      (net 499 "/Xilinx K26 SOM/HPC14_N") (pinfunction "A36") (pintype "passive"))
    (pad "A37" smd circle (at -4.128 -1.75 270) (size 0.356 0.356) (layers "F.Cu" "F.Paste" "F.Mask")
      (net 1 "GND") (pinfunction "A37") (pintype "passive"))
    (pad "A38" smd circle (at -4.763 -1.75 270) (size 0.356 0.356) (layers "F.Cu" "F.Paste" "F.Mask")
      (net 500 "/Xilinx K26 SOM/HPC15_CC_P") (pinfunction "A38") (pintype "passive"))
    (pad "A39" smd circle (at -5.398 -1.75 270) (size 0.356 0.356) (layers "F.Cu" "F.Paste" "F.Mask")
      (net 501 "/Xilinx K26 SOM/HPC15_CC_N") (pinfunction "A39") (pintype "passive"))
    (pad "A40" smd circle (at -6.033 -1.75 270) (size 0.356 0.356) (layers "F.Cu" "F.Paste" "F.Mask")
      (net 1 "GND") (pinfunction "A40") (pintype "passive"))
    (pad "A41" smd circle (at -6.668 -1.75 270) (size 0.356 0.356) (layers "F.Cu" "F.Paste" "F.Mask")
      (net 502 "/Xilinx K26 SOM/HPC03_P") (pinfunction "A41") (pintype "passive"))
    (pad "A42" smd circle (at -7.303 -1.75 270) (size 0.356 0.356) (layers "F.Cu" "F.Paste" "F.Mask")
      (net 503 "/Xilinx K26 SOM/HPC03_N") (pinfunction "A42") (pintype "passive"))
    (pad "A43" smd circle (at -7.938 -1.75 270) (size 0.356 0.356) (layers "F.Cu" "F.Paste" "F.Mask")
      (net 1 "GND") (pinfunction "A43") (pintype "passive"))
    (pad "A44" smd circle (at -8.573 -1.75 270) (size 0.356 0.356) (layers "F.Cu" "F.Paste" "F.Mask")
      (net 504 "/Xilinx K26 SOM/VCCO_HPB_1") (pinfunction "A44") (pintype "passive"))
    (pad "A45" smd circle (at -9.208 -1.75 270) (size 0.356 0.356) (layers "F.Cu" "F.Paste" "F.Mask")
      (net 1 "GND") (pinfunction "A45") (pintype "passive"))
    (pad "A46" smd circle (at -9.843 -1.75 270) (size 0.356 0.356) (layers "F.Cu" "F.Paste" "F.Mask")
      (net 505 "/Xilinx K26 SOM/HDB18") (pinfunction "A46") (pintype "passive"))
    (pad "A47" smd circle (at -10.478 -1.75 270) (size 0.356 0.356) (layers "F.Cu" "F.Paste" "F.Mask")
      (net 506 "/Xilinx K26 SOM/HDB19") (pinfunction "A47") (pintype "passive"))
    (pad "A48" smd circle (at -11.113 -1.75 270) (size 0.356 0.356) (layers "F.Cu" "F.Paste" "F.Mask")
      (net 507 "/Xilinx K26 SOM/HDB20") (pinfunction "A48") (pintype "passive"))
    (pad "A49" smd circle (at -11.748 -1.75 270) (size 0.356 0.356) (layers "F.Cu" "F.Paste" "F.Mask")
      (net 1 "GND") (pinfunction "A49") (pintype "passive"))
    (pad "A50" smd circle (at -12.383 -1.75 270) (size 0.356 0.356) (layers "F.Cu" "F.Paste" "F.Mask")
      (net 508 "/Xilinx K26 SOM/HDB21") (pinfunction "A50") (pintype "passive"))
    (pad "A51" smd circle (at -13.018 -1.75 270) (size 0.356 0.356) (layers "F.Cu" "F.Paste" "F.Mask")
      (net 509 "/Xilinx K26 SOM/HDB22") (pinfunction "A51") (pintype "passive"))
    (pad "A52" smd circle (at -13.653 -1.75 270) (size 0.356 0.356) (layers "F.Cu" "F.Paste" "F.Mask")
      (net 510 "/Xilinx K26 SOM/HDB23") (pinfunction "A52") (pintype "passive"))
    (pad "A53" smd circle (at -14.288 -1.75 270) (size 0.356 0.356) (layers "F.Cu" "F.Paste" "F.Mask")
      (net 1 "GND") (pinfunction "A53") (pintype "passive"))
    (pad "A54" smd circle (at -14.923 -1.75 270) (size 0.356 0.356) (layers "F.Cu" "F.Paste" "F.Mask")
      (net 511 "/Xilinx K26 SOM/HDC18") (pinfunction "A54") (pintype "passive"))
    (pad "A55" smd circle (at -15.558 -1.75 270) (size 0.356 0.356) (layers "F.Cu" "F.Paste" "F.Mask")
      (net 512 "/Xilinx K26 SOM/HDC19") (pinfunction "A55") (pintype "passive"))
    (pad "A56" smd circle (at -16.193 -1.75 270) (size 0.356 0.356) (layers "F.Cu" "F.Paste" "F.Mask")
      (net 513 "/Xilinx K26 SOM/HDC20") (pinfunction "A56") (pintype "passive"))
    (pad "A57" smd circle (at -16.828 -1.75 270) (size 0.356 0.356) (layers "F.Cu" "F.Paste" "F.Mask")
      (net 1 "GND") (pinfunction "A57") (pintype "passive"))
    (pad "A58" smd circle (at -17.463 -1.75 270) (size 0.356 0.356) (layers "F.Cu" "F.Paste" "F.Mask")
      (net 514 "/Xilinx K26 SOM/HDC21") (pinfunction "A58") (pintype "passive"))
    (pad "A59" smd circle (at -18.098 -1.75 270) (size 0.356 0.356) (layers "F.Cu" "F.Paste" "F.Mask")
      (net 515 "/Xilinx K26 SOM/HDC22") (pinfunction "A59") (pintype "passive"))
    (pad "A60" smd circle (at -18.733 -1.75 270) (size 0.356 0.356) (layers "F.Cu" "F.Paste" "F.Mask")
      (net 516 "/Xilinx K26 SOM/HDC23") (pinfunction "A60") (pintype "passive"))
    (pad "B01" smd circle (at 18.732 -0.791 270) (size 0.356 0.356) (layers "F.Cu" "F.Paste" "F.Mask")
      (net 517 "/Xilinx K26 SOM/GTH_DP2_C2M_P") (pinfunction "B01") (pintype "passive"))
    (pad "B02" smd circle (at 18.097 -0.791 270) (size 0.356 0.356) (layers "F.Cu" "F.Paste" "F.Mask")
      (net 518 "/Xilinx K26 SOM/GTH_DP2_C2M_N") (pinfunction "B02") (pintype "passive"))
    (pad "B03" smd circle (at 17.462 -0.791 270) (size 0.356 0.356) (layers "F.Cu" "F.Paste" "F.Mask")
      (net 1 "GND") (pinfunction "B03") (pintype "passive"))
    (pad "B04" smd circle (at 16.827 -0.791 270) (size 0.356 0.356) (layers "F.Cu" "F.Paste" "F.Mask")
      (net 1 "GND") (pinfunction "B04") (pintype "passive"))
    (pad "B05" smd circle (at 16.192 -0.791 270) (size 0.356 0.356) (layers "F.Cu" "F.Paste" "F.Mask")
      (net 519 "/Xilinx K26 SOM/GTH_DP2_M2C_P") (pinfunction "B05") (pintype "passive"))
    (pad "B06" smd circle (at 15.557 -0.791 270) (size 0.356 0.356) (layers "F.Cu" "F.Paste" "F.Mask")
      (net 520 "/Xilinx K26 SOM/GTH_DP2_M2C_N") (pinfunction "B06") (pintype "passive"))
    (pad "B07" smd circle (at 14.922 -0.791 270) (size 0.356 0.356) (layers "F.Cu" "F.Paste" "F.Mask")
      (net 1 "GND") (pinfunction "B07") (pintype "passive"))
    (pad "B08" smd circle (at 14.287 -0.791 270) (size 0.356 0.356) (layers "F.Cu" "F.Paste" "F.Mask")
      (net 1 "GND") (pinfunction "B08") (pintype "passive"))
    (pad "B09" smd circle (at 13.652 -0.791 270) (size 0.356 0.356) (layers "F.Cu" "F.Paste" "F.Mask")
      (net 521 "/Xilinx K26 SOM/GTH_DP0_C2M_P") (pinfunction "B09") (pintype "passive"))
    (pad "B10" smd circle (at 13.017 -0.791 270) (size 0.356 0.356) (layers "F.Cu" "F.Paste" "F.Mask")
      (net 522 "/Xilinx K26 SOM/GTH_DP0_C2M_N") (pinfunction "B10") (pintype "passive"))
    (pad "B11" smd circle (at 12.382 -0.791 270) (size 0.356 0.356) (layers "F.Cu" "F.Paste" "F.Mask")
      (net 1 "GND") (pinfunction "B11") (pintype "passive"))
    (pad "B12" smd circle (at 11.747 -0.791 270) (size 0.356 0.356) (layers "F.Cu" "F.Paste" "F.Mask")
      (net 523 "/Xilinx K26 SOM/HPB10_CC_P") (pinfunction "B12") (pintype "passive"))
    (pad "B13" smd circle (at 11.112 -0.791 270) (size 0.356 0.356) (layers "F.Cu" "F.Paste" "F.Mask")
      (net 524 "/Xilinx K26 SOM/HPB10_CC_N") (pinfunction "B13") (pintype "passive"))
    (pad "B14" smd circle (at 10.477 -0.791 270) (size 0.356 0.356) (layers "F.Cu" "F.Paste" "F.Mask")
      (net 1 "GND") (pinfunction "B14") (pintype "passive"))
    (pad "B15" smd circle (at 9.842 -0.791 270) (size 0.356 0.356) (layers "F.Cu" "F.Paste" "F.Mask")
      (net 525 "/Xilinx K26 SOM/HPB07_P") (pinfunction "B15") (pintype "passive"))
    (pad "B16" smd circle (at 9.207 -0.791 270) (size 0.356 0.356) (layers "F.Cu" "F.Paste" "F.Mask")
      (net 526 "/Xilinx K26 SOM/HPB07_N") (pinfunction "B16") (pintype "passive"))
    (pad "B17" smd circle (at 8.572 -0.791 270) (size 0.356 0.356) (layers "F.Cu" "F.Paste" "F.Mask")
      (net 1 "GND") (pinfunction "B17") (pintype "passive"))
    (pad "B18" smd circle (at 7.937 -0.791 270) (size 0.356 0.356) (layers "F.Cu" "F.Paste" "F.Mask")
      (net 527 "/Xilinx K26 SOM/HPB05_CC_P") (pinfunction "B18") (pintype "passive"))
    (pad "B19" smd circle (at 7.302 -0.791 270) (size 0.356 0.356) (layers "F.Cu" "F.Paste" "F.Mask")
      (net 528 "/Xilinx K26 SOM/HPB05_CC_N") (pinfunction "B19") (pintype "passive"))
    (pad "B20" smd circle (at 6.667 -0.791 270) (size 0.356 0.356) (layers "F.Cu" "F.Paste" "F.Mask")
      (net 1 "GND") (pinfunction "B20") (pintype "passive"))
    (pad "B21" smd circle (at 6.032 -0.791 270) (size 0.356 0.356) (layers "F.Cu" "F.Paste" "F.Mask")
      (net 529 "/Xilinx K26 SOM/HPB11_P") (pinfunction "B21") (pintype "passive"))
    (pad "B22" smd circle (at 5.397 -0.791 270) (size 0.356 0.356) (layers "F.Cu" "F.Paste" "F.Mask")
      (net 530 "/Xilinx K26 SOM/HPB11_N") (pinfunction "B22") (pintype "passive"))
    (pad "B23" smd circle (at 4.762 -0.791 270) (size 0.356 0.356) (layers "F.Cu" "F.Paste" "F.Mask")
      (net 1 "GND") (pinfunction "B23") (pintype "passive"))
    (pad "B24" smd circle (at 4.127 -0.791 270) (size 0.356 0.356) (layers "F.Cu" "F.Paste" "F.Mask")
      (net 531 "/Xilinx K26 SOM/HPB03_P") (pinfunction "B24") (pintype "passive"))
    (pad "B25" smd circle (at 3.492 -0.791 270) (size 0.356 0.356) (layers "F.Cu" "F.Paste" "F.Mask")
      (net 532 "/Xilinx K26 SOM/HPB03_N") (pinfunction "B25") (pintype "passive"))
    (pad "B26" smd circle (at 2.857 -0.791 270) (size 0.356 0.356) (layers "F.Cu" "F.Paste" "F.Mask")
      (net 1 "GND") (pinfunction "B26") (pintype "passive"))
    (pad "B27" smd circle (at 2.222 -0.791 270) (size 0.356 0.356) (layers "F.Cu" "F.Paste" "F.Mask")
      (net 533 "/Xilinx K26 SOM/HPC06_P") (pinfunction "B27") (pintype "passive"))
    (pad "B28" smd circle (at 1.587 -0.791 270) (size 0.356 0.356) (layers "F.Cu" "F.Paste" "F.Mask")
      (net 534 "/Xilinx K26 SOM/HPC06_N") (pinfunction "B28") (pintype "passive"))
    (pad "B29" smd circle (at 0.952 -0.791 270) (size 0.356 0.356) (layers "F.Cu" "F.Paste" "F.Mask")
      (net 1 "GND") (pinfunction "B29") (pintype "passive"))
    (pad "B30" smd circle (at 0.317 -0.791 270) (size 0.356 0.356) (layers "F.Cu" "F.Paste" "F.Mask")
      (net 535 "/Xilinx K26 SOM/HPC13_P") (pinfunction "B30") (pintype "passive"))
    (pad "B31" smd circle (at -0.318 -0.791 270) (size 0.356 0.356) (layers "F.Cu" "F.Paste" "F.Mask")
      (net 536 "/Xilinx K26 SOM/HPC13_N") (pinfunction "B31") (pintype "passive"))
    (pad "B32" smd circle (at -0.953 -0.791 270) (size 0.356 0.356) (layers "F.Cu" "F.Paste" "F.Mask")
      (net 1 "GND") (pinfunction "B32") (pintype "passive"))
    (pad "B33" smd circle (at -1.588 -0.791 270) (size 0.356 0.356) (layers "F.Cu" "F.Paste" "F.Mask")
      (net 537 "/Xilinx K26 SOM/HPC16_P") (pinfunction "B33") (pintype "passive"))
    (pad "B34" smd circle (at -2.223 -0.791 270) (size 0.356 0.356) (layers "F.Cu" "F.Paste" "F.Mask")
      (net 538 "/Xilinx K26 SOM/HPC16_N") (pinfunction "B34") (pintype "passive"))
    (pad "B35" smd circle (at -2.858 -0.791 270) (size 0.356 0.356) (layers "F.Cu" "F.Paste" "F.Mask")
      (net 1 "GND") (pinfunction "B35") (pintype "passive"))
    (pad "B36" smd circle (at -3.493 -0.791 270) (size 0.356 0.356) (layers "F.Cu" "F.Paste" "F.Mask")
      (net 539 "/Xilinx K26 SOM/HPC07_P") (pinfunction "B36") (pintype "passive"))
    (pad "B37" smd circle (at -4.128 -0.791 270) (size 0.356 0.356) (layers "F.Cu" "F.Paste" "F.Mask")
      (net 540 "/Xilinx K26 SOM/HPC07_N") (pinfunction "B37") (pintype "passive"))
    (pad "B38" smd circle (at -4.763 -0.791 270) (size 0.356 0.356) (layers "F.Cu" "F.Paste" "F.Mask")
      (net 1 "GND") (pinfunction "B38") (pintype "passive"))
  )
)
